#ISCELL
  mstr_misc dns *
  *
#ISCELL
  pure_quanta quanta_title_block_c *
  *
#ISCELL
  pure_quanta_power design_note *
  *
#ISCELL
  standard offpage *
  page340_i1
#ISCELL
  standard offpage *
  page340_i100
#CELL
  pure_quanta q_res *
  page340_i101
#CELL
  pure_quanta q_res *
  page340_i102
#ISCELL
  standard offpage *
  page340_i12
#CELL
  pure_quanta q_res *
  page340_i13
#CELL
  pure_quanta q_res *
  page340_i14
#CELL
  pure_quanta q_res *
  page340_i15
#ISCELL
  pure_quanta_power universal_gnd *
  page340_i16
#CELL
  pure_quanta q_res *
  page340_i18
#ISCELL
  pure_quanta_power universal_gnd *
  page340_i19
#CELL
  pure_quanta q_res *
  page340_i2
#ISCELL
  pure_quanta_power universal_power *
  page340_i21
#CELL
  pure_quanta q_res *
  page340_i22
#ISCELL
  standard offpage *
  page340_i23
#ISCELL
  pure_quanta_power universal_gnd *
  page340_i24
#CELL
  pure_quanta 74lvc1g08w57 *
  page340_i25
#ISCELL
  pure_quanta_power universal_gnd *
  page340_i26
#CELL
  pure_quanta q_cap *
  page340_i27
#ISCELL
  pure_quanta_power universal_power *
  page340_i28
#CELL
  pure_quanta q_res *
  page340_i29
#CELL
  pure_quanta q_res *
  page340_i3
#ISCELL
  standard offpage *
  page340_i30
#CELL
  pure_quanta mosfet_n *
  page340_i31
#ISCELL
  pure_quanta_power universal_gnd *
  page340_i32
#ISCELL
  standard offpage *
  page340_i33
#CELL
  pure_quanta q_res *
  page340_i34
#ISCELL
  pure_quanta_power universal_power *
  page340_i35
#CELL
  pure_quanta 74lvc1g08w57 *
  page340_i36
#ISCELL
  pure_quanta_power universal_gnd *
  page340_i37
#ISCELL
  pure_quanta_power universal_power *
  page340_i39
#ISCELL
  pure_quanta_power universal_power *
  page340_i4
#CELL
  pure_quanta q_cap *
  page340_i40
#ISCELL
  pure_quanta_power universal_gnd *
  page340_i41
#ISCELL
  pure_quanta_power universal_power *
  page340_i43
#CELL
  pure_quanta q_res *
  page340_i44
#CELL
  pure_quanta q_res *
  page340_i47
#ISCELL
  standard offpage *
  page340_i48
#CELL
  pure_quanta q_res *
  page340_i49
#ISCELL
  standard offpage *
  page340_i50
#CELL
  pure_quanta sn74lvc1g07dbvr *
  page340_i51
#ISCELL
  pure_quanta_power universal_power *
  page340_i52
#CELL
  pure_quanta q_cap *
  page340_i53
#ISCELL
  pure_quanta_power universal_gnd *
  page340_i54
#ISCELL
  pure_quanta_power universal_gnd *
  page340_i55
#ISCELL
  standard offpage *
  page340_i56
#CELL
  pure_quanta q_res *
  page340_i57
#CELL
  pure_quanta q_res *
  page340_i58
#ISCELL
  standard offpage *
  page340_i59
#ISCELL
  pure_quanta_power universal_power *
  page340_i60
#CELL
  pure_quanta q_res *
  page340_i61
#ISCELL
  standard offpage *
  page340_i62
#ISCELL
  pure_quanta_power universal_power *
  page340_i63
#CELL
  pure_quanta q_res *
  page340_i64
#CELL
  pure_quanta q_res *
  page340_i65
#CELL
  pure_quanta sn74lvc1g07dbvr *
  page340_i66
#ISCELL
  pure_quanta_power universal_gnd *
  page340_i67
#ISCELL
  pure_quanta_power universal_power *
  page340_i68
#CELL
  pure_quanta q_cap *
  page340_i69
#ISCELL
  pure_quanta_power universal_gnd *
  page340_i70
#CELL
  pure_quanta q_res *
  page340_i71
#ISCELL
  standard offpage *
  page340_i72
#ISCELL
  standard offpage *
  page340_i73
#CELL
  pure_quanta 74lvc1g32gw *
  page340_i74
#CELL
  pure_quanta q_cap *
  page340_i75
#CELL
  pure_quanta q_res *
  page340_i76
#ISCELL
  pure_quanta_power universal_power *
  page340_i77
#ISCELL
  pure_quanta_power universal_gnd *
  page340_i78
#CELL
  pure_quanta q_cap *
  page340_i79
#CELL
  pure_quanta apx80929sag7 *
  page340_i80
#ISCELL
  pure_quanta_power universal_power *
  page340_i81
#ISCELL
  pure_quanta_power universal_gnd *
  page340_i82
#ISCELL
  pure_quanta_power universal_gnd *
  page340_i83
#CELL
  pure_quanta q_res *
  page340_i84
#CELL
  pure_quanta q_res *
  page340_i85
#ISCELL
  standard offpage *
  page340_i86
#ISCELL
  pure_quanta_power universal_power *
  page340_i87
#CELL
  pure_quanta q_res *
  page340_i90
#CELL
  pure_quanta 74lvc1g08w57 *
  page340_i91
#ISCELL
  pure_quanta_power universal_gnd *
  page340_i92
#ISCELL
  pure_quanta_power universal_power *
  page340_i93
#CELL
  pure_quanta q_cap *
  page340_i94
#ISCELL
  pure_quanta_power universal_gnd *
  page340_i95
#CELL
  pure_quanta q_res *
  page340_i96
#ISCELL
  standard offpage *
  page340_i97
#ISCELL
  standard offpage *
  page340_i98
#ISCELL
  standard offpage *
  page340_i99
